# S9S_MB_2U (Grand Teton) — schematic netlist excerpt (pin names and nets, part order shuffled) for the footprints in the layout excerpt that follows; sources: Cadence DE-HDL packaged netlist, KiCad conversion of 03242023_DA0F0TMBIJ0_F0T_Motherboard_J_brd_V01_OCP.brd

PC622  Q_CAPP  270UF 16V 20% OSCON  pkg THLF  page 271 : A = SW_P12V_PVCCFA_EHV_FIVRA_CPU0_L ; B = GND
R2456  Q_RES  33.2 1% CHIP  pkg 0402LF  page 241 : A = SMB_VR_3V3AUX_SDA_R ; B = SMB_VR_3V3AUX_SDA_R3
PC2167  Q_CAP  100PF 50V 5% X7R  pkg 0402  page 163 : A = P12V_OCP_IMON_2 ; B = GND

(kicad_pcb
	(version 20260206)
	(generator "pcbnew")
	(generator_version "10.0")
	(general
		(thickness 1.6)
		(legacy_teardrops no)
	)
	(paper "A4")
	(title_block
		(title "03242023_DA0F0TMBIJ0_F0T_Motherboard_J_brd_V01_OCP.brd")
		(comment 1 "Grand Teton / footprints 634-636 of 6105")
	)
	(layers
		(0 "F.Cu" signal "TOP")
		(4 "In1.Cu" signal "GND")
		(6 "In2.Cu" signal "IN1")
		(8 "In3.Cu" signal "GND1")
		(10 "In4.Cu" signal "IN2")
		(12 "In5.Cu" signal "GND2")
		(14 "In6.Cu" signal "IN3")
		(16 "In7.Cu" signal "GND3")
		(18 "In8.Cu" signal "VCC")
		(20 "In9.Cu" signal "VCC1")
		(22 "In10.Cu" signal "GND4")
		(24 "In11.Cu" signal "IN4")
		(26 "In12.Cu" signal "GND5")
		(28 "In13.Cu" signal "IN5")
		(30 "In14.Cu" signal "GND6")
		(32 "In15.Cu" signal "IN6")
		(34 "In16.Cu" signal "GND7")
		(2 "B.Cu" signal "BOTTOM")
		(9 "F.Adhes" user "F.Adhesive")
		(11 "B.Adhes" user "B.Adhesive")
		(13 "F.Paste" user "Package Geometry/Pastemask Top")
		(15 "B.Paste" user "Package Geometry/Pastemask Bottom")
		(5 "F.SilkS" user "Ref Des/Silkscreen Top")
		(7 "B.SilkS" user "Ref Des/Silkscreen Bottom")
		(1 "F.Mask" user "Board Geometry/Soldermask Top")
		(3 "B.Mask" user "Board Geometry/Soldermask Bottom")
		(17 "Dwgs.User" user "User.Drawings")
		(19 "Cmts.User" user "User.Comments")
		(21 "Eco1.User" user "User.Eco1")
		(23 "Eco2.User" user "User.Eco2")
		(25 "Edge.Cuts" user "Board Geometry/Outline")
		(27 "Margin" user)
		(31 "F.CrtYd" user "Package Geometry/Place Bound Top")
		(29 "B.CrtYd" user "Package Geometry/Place Bound Bottom")
		(35 "F.Fab" user "Ref Des/Assembly Top")
		(33 "B.Fab" user "Ref Des/Assembly Bottom")
	)
	(footprint ""
		(layer "F.Cu")
		(at 101.071172 -363.873034)
		(property "Reference" "R2456"
			(at 0 0 0)
			(layer "F.SilkS")
			(hide yes)
			(effects
				(font
					(size 1.27 1.27)
				)
			)
		)
		(property "Value" ""
			(at 0 0 0)
			(layer "F.Fab")
			(effects
				(font
					(size 1.27 1.27)
				)
			)
		)
		(duplicate_pad_numbers_are_jumpers no)
		(fp_line
			(start -0.7874 -0.4064)
			(end 0.7874 -0.4064)
			(stroke
				(width 0.1524)
				(type default)
			)
			(layer "F.SilkS")
		)
		(fp_line
			(start -0.7874 0.4064)
			(end -0.7874 -0.4064)
			(stroke
				(width 0.1524)
				(type default)
			)
			(layer "F.SilkS")
		)
		(fp_line
			(start 0.7874 -0.4064)
			(end 0.7874 0.4064)
			(stroke
				(width 0.1524)
				(type default)
			)
			(layer "F.SilkS")
		)
		(fp_line
			(start 0.7874 0.4064)
			(end -0.7874 0.4064)
			(stroke
				(width 0.1524)
				(type default)
			)
			(layer "F.SilkS")
		)
		(fp_line
			(start -0.67945 -0.305054)
			(end -0.12065 -0.305054)
			(stroke
				(width 0.1)
				(type default)
			)
			(layer "F.Fab")
		)
		(fp_line
			(start -0.67945 0.3048)
			(end -0.67945 -0.305054)
			(stroke
				(width 0.1)
				(type default)
			)
			(layer "F.Fab")
		)
		(fp_line
			(start -0.12065 -0.305054)
			(end -0.12065 -0.2794)
			(stroke
				(width 0.1)
				(type default)
			)
			(layer "F.Fab")
		)
		(fp_line
			(start -0.12065 -0.2794)
			(end 0.12065 -0.2794)
			(stroke
				(width 0.1)
				(type default)
			)
			(layer "F.Fab")
		)
		(fp_line
			(start -0.12065 0.2794)
			(end -0.12065 0.3048)
			(stroke
				(width 0.1)
				(type default)
			)
			(layer "F.Fab")
		)
		(fp_line
			(start -0.12065 0.3048)
			(end -0.67945 0.3048)
			(stroke
				(width 0.1)
				(type default)
			)
			(layer "F.Fab")
		)
		(fp_line
			(start 0.120396 0.2794)
			(end -0.12065 0.2794)
			(stroke
				(width 0.1)
				(type default)
			)
			(layer "F.Fab")
		)
		(fp_line
			(start 0.120396 0.3048)
			(end 0.120396 0.2794)
			(stroke
				(width 0.1)
				(type default)
			)
			(layer "F.Fab")
		)
		(fp_line
			(start 0.12065 -0.3048)
			(end 0.67945 -0.3048)
			(stroke
				(width 0.1)
				(type default)
			)
			(layer "F.Fab")
		)
		(fp_line
			(start 0.12065 -0.2794)
			(end 0.12065 -0.3048)
			(stroke
				(width 0.1)
				(type default)
			)
			(layer "F.Fab")
		)
		(fp_line
			(start 0.67945 -0.3048)
			(end 0.67945 0.3048)
			(stroke
				(width 0.1)
				(type default)
			)
			(layer "F.Fab")
		)
		(fp_line
			(start 0.67945 0.3048)
			(end 0.120396 0.3048)
			(stroke
				(width 0.1)
				(type default)
			)
			(layer "F.Fab")
		)
		(pad "1" smd circle
			(at -0.40005 0)
			(size 0 0)
			(layers "F.Cu" "F.Mask" "F.Paste")
			(net "SMB_VR_3V3AUX_SDA_R")
		)
		(pad "2" smd circle
			(at 0.40005 0)
			(size 0 0)
			(layers "F.Cu" "F.Mask" "F.Paste")
			(net "SMB_VR_3V3AUX_SDA_R3")
		)
	)
	(footprint ""
		(layer "F.Cu")
		(at 296.831258 -372.456202 90)
		(property "Reference" "PC622"
			(at 0 0 90)
			(layer "F.SilkS")
			(hide yes)
			(effects
				(font
					(size 1.27 1.27)
				)
			)
		)
		(property "Value" ""
			(at 0 0 90)
			(layer "F.Fab")
			(effects
				(font
					(size 1.27 1.27)
				)
			)
		)
		(duplicate_pad_numbers_are_jumpers no)
		(fp_line
			(start -3.400044 1.249934)
			(end 3.400044 1.249934)
			(stroke
				(width 0.1524)
				(type default)
			)
			(layer "F.SilkS")
		)
		(fp_circle
			(center 0 1.249934)
			(end 0 4.649978)
			(stroke
				(width 0.1524)
				(type default)
			)
			(fill no)
			(layer "F.SilkS")
		)
		(fp_poly
			(pts
				(arc
					(start -3.400044 1.249934)
					(mid 0 4.649978)
					(end 3.400044 1.249934)
				)
			)
			(stroke
				(width 0)
				(type default)
			)
			(fill yes)
			(layer "F.SilkS")
		)
		(fp_circle
			(center 0 1.249934)
			(end 0 4.649978)
			(stroke
				(width 0.1)
				(type default)
			)
			(fill no)
			(layer "F.Fab")
		)
		(pad "1" thru_hole rect
			(at 0 0 90)
			(size 1.524 1.524)
			(drill 1.016)
			(layers "*.Cu" "*.Mask")
			(remove_unused_layers no)
			(net "SW_P12V_PVCCFA_EHV_FIVRA_CPU0_L")
			(clearance 0)
			(padstack
				(mode front_inner_back)
				(layer "Inner"
					(shape circle)
					(size 1.524 1.524)
					(clearance 0)
				)
				(layer "B.Cu"
					(shape rect)
					(size 1.524 1.524)
					(clearance 0)
				)
			)
		)
		(pad "2" thru_hole circle
			(at 0 2.500122 90)
			(size 1.524 1.524)
			(drill 1.016)
			(layers "*.Cu" "*.Mask")
			(remove_unused_layers no)
			(net "GND")
			(clearance 0)
		)
	)
	(footprint ""
		(layer "F.Cu")
		(at 64.591438 -31.887922 90)
		(property "Reference" "PC2167"
			(at 0 0 90)
			(layer "F.SilkS")
			(hide yes)
			(effects
				(font
					(size 1.27 1.27)
				)
			)
		)
		(property "Value" ""
			(at 0 0 90)
			(layer "F.Fab")
			(effects
				(font
					(size 1.27 1.27)
				)
			)
		)
		(duplicate_pad_numbers_are_jumpers no)
		(fp_line
			(start 0.7874 -0.4064)
			(end 0.7874 0.4064)
			(stroke
				(width 0.1524)
				(type default)
			)
			(layer "F.SilkS")
		)
		(fp_line
			(start -0.7874 -0.4064)
			(end 0.7874 -0.4064)
			(stroke
				(width 0.1524)
				(type default)
			)
			(layer "F.SilkS")
		)
		(fp_line
			(start 0.7874 0.4064)
			(end -0.7874 0.4064)
			(stroke
				(width 0.1524)
				(type default)
			)
			(layer "F.SilkS")
		)
		(fp_line
			(start -0.7874 0.4064)
			(end -0.7874 -0.4064)
			(stroke
				(width 0.1524)
				(type default)
			)
			(layer "F.SilkS")
		)
		(fp_line
			(start -0.12065 -0.305054)
			(end -0.12065 -0.2794)
			(stroke
				(width 0.1)
				(type default)
			)
			(layer "F.Fab")
		)
		(fp_line
			(start -0.67945 -0.305054)
			(end -0.12065 -0.305054)
			(stroke
				(width 0.1)
				(type default)
			)
			(layer "F.Fab")
		)
		(fp_line
			(start 0.67945 -0.3048)
			(end 0.67945 0.3048)
			(stroke
				(width 0.1)
				(type default)
			)
			(layer "F.Fab")
		)
		(fp_line
			(start 0.12065 -0.3048)
			(end 0.67945 -0.3048)
			(stroke
				(width 0.1)
				(type default)
			)
			(layer "F.Fab")
		)
		(fp_line
			(start 0.12065 -0.2794)
			(end 0.12065 -0.3048)
			(stroke
				(width 0.1)
				(type default)
			)
			(layer "F.Fab")
		)
		(fp_line
			(start -0.12065 -0.2794)
			(end 0.12065 -0.2794)
			(stroke
				(width 0.1)
				(type default)
			)
			(layer "F.Fab")
		)
		(fp_line
			(start 0.120396 0.2794)
			(end -0.12065 0.2794)
			(stroke
				(width 0.1)
				(type default)
			)
			(layer "F.Fab")
		)
		(fp_line
			(start -0.12065 0.2794)
			(end -0.12065 0.3048)
			(stroke
				(width 0.1)
				(type default)
			)
			(layer "F.Fab")
		)
		(fp_line
			(start 0.67945 0.3048)
			(end 0.120396 0.3048)
			(stroke
				(width 0.1)
				(type default)
			)
			(layer "F.Fab")
		)
		(fp_line
			(start 0.120396 0.3048)
			(end 0.120396 0.2794)
			(stroke
				(width 0.1)
				(type default)
			)
			(layer "F.Fab")
		)
		(fp_line
			(start -0.12065 0.3048)
			(end -0.67945 0.3048)
			(stroke
				(width 0.1)
				(type default)
			)
			(layer "F.Fab")
		)
		(fp_line
			(start -0.67945 0.3048)
			(end -0.67945 -0.305054)
			(stroke
				(width 0.1)
				(type default)
			)
			(layer "F.Fab")
		)
		(pad "1" smd circle
			(at -0.40005 0 90)
			(size 0 0)
			(layers "F.Cu" "F.Mask" "F.Paste")
			(net "P12V_OCP_IMON_2")
		)
		(pad "2" smd circle
			(at 0.40005 0 90)
			(size 0 0)
			(layers "F.Cu" "F.Mask" "F.Paste")
			(net "GND")
		)
	)
)
